(kicad_pcb
	(version 20260206)
	(generator "pcbnew")
	(generator_version "10.0")
	(general
		(thickness 1.6)
		(legacy_teardrops no)
	)
	(paper "A4")
	(title_block
		(title "Bryce Canyon_F.DPB_16315-1-OCP.brd")
		(comment 1 "Bryce Canyon / footprints 1495-1502 of 2223")
	)
	(layers
		(0 "F.Cu" signal "TOP")
		(4 "In1.Cu" signal "L2GND")
		(6 "In2.Cu" signal "L3")
		(8 "In3.Cu" signal "L4GND")
		(10 "In4.Cu" signal "L5")
		(12 "In5.Cu" signal "L6VCC")
		(14 "In6.Cu" signal "L7VCC")
		(16 "In7.Cu" signal "L8")
		(18 "In8.Cu" signal "L9GND")
		(20 "In9.Cu" signal "L10")
		(22 "In10.Cu" signal "L11GND")
		(2 "B.Cu" signal "BOTTOM")
		(9 "F.Adhes" user "F.Adhesive")
		(11 "B.Adhes" user "B.Adhesive")
		(13 "F.Paste" user "Package Geometry/Pastemask Top")
		(15 "B.Paste" user "Package Geometry/Pastemask Bottom")
		(5 "F.SilkS" user "Ref Des/Silkscreen Top")
		(7 "B.SilkS" user "Ref Des/Silkscreen Bottom")
		(1 "F.Mask" user "Board Geometry/Soldermask Top")
		(3 "B.Mask" user "Board Geometry/Soldermask Bottom")
		(17 "Dwgs.User" user "User.Drawings")
		(19 "Cmts.User" user "User.Comments")
		(21 "Eco1.User" user "User.Eco1")
		(23 "Eco2.User" user "User.Eco2")
		(25 "Edge.Cuts" user "Board Geometry/Outline")
		(27 "Margin" user)
		(31 "F.CrtYd" user "Package Geometry/Place Bound Top")
		(29 "B.CrtYd" user "Package Geometry/Place Bound Bottom")
		(35 "F.Fab" user "Ref Des/Assembly Top")
		(33 "B.Fab" user "Ref Des/Assembly Bottom")
	)
	(footprint ""
		(layer "F.Cu")
		(at 242.57 -249.174 180)
		(property "Reference" "R45"
			(at 0 0 180)
			(layer "F.SilkS")
			(hide yes)
			(effects
				(font
					(size 1.27 1.27)
				)
			)
		)
		(property "Value" "4K7R2F-GP"
			(at 0.064008 -3.993896 180)
			(unlocked yes)
			(layer "F.Fab")
			(hide yes)
			(effects
				(font
					(size 1.016 1.016)
					(thickness 0.1524)
				)
			)
		)
		(property "Device Type" "R402H16"
			(at 0.064008 -5.517896 180)
			(unlocked yes)
			(layer "F.Fab")
			(hide yes)
			(effects
				(font
					(size 1.016 1.016)
					(thickness 0.1524)
				)
			)
		)
		(duplicate_pad_numbers_are_jumpers no)
		(fp_line
			(start 0.508 -0.9398)
			(end -0.508 -0.9398)
			(stroke
				(width 0.1524)
				(type default)
			)
			(layer "F.SilkS")
		)
		(fp_line
			(start -0.508 -0.9398)
			(end -0.508 0.9398)
			(stroke
				(width 0.1524)
				(type default)
			)
			(layer "F.SilkS")
		)
		(fp_rect
			(start -0.508 0.9398)
			(end 0.508 -0.9398)
			(stroke
				(width 0)
				(type default)
			)
			(fill no)
			(layer "F.CrtYd")
		)
		(fp_rect
			(start -0.508 0.9398)
			(end 0.508 -0.9398)
			(stroke
				(width 0)
				(type default)
			)
			(fill no)
			(layer "F.Fab")
		)
		(pad "1" smd custom
			(at 0 -0.4445 180)
			(size 0.1397 0.1397)
			(layers "F.Cu" "F.Mask" "F.Paste")
			(net "P3V3_STBY_A")
			(options
				(clearance outline)
				(anchor circle)
			)
			(primitives
				(gr_poly
					(pts
						(arc
							(start -0.1778 -0.2794)
							(mid -0.249642 -0.249642)
							(end -0.2794 -0.1778)
						)
						(arc
							(start -0.2794 0.1778)
							(mid -0.249642 0.249642)
							(end -0.1778 0.2794)
						)
						(arc
							(start 0.1778 0.2794)
							(mid 0.249642 0.249642)
							(end 0.2794 0.1778)
						)
						(arc
							(start 0.2794 -0.1778)
							(mid 0.249642 -0.249642)
							(end 0.1778 -0.2794)
						)
					)
					(width 0)
					(fill yes)
				)
			)
		)
		(pad "2" smd custom
			(at 0 0.4445 180)
			(size 0.1397 0.1397)
			(layers "F.Cu" "F.Mask" "F.Paste")
			(net "IO_EXP5_A1")
			(options
				(clearance outline)
				(anchor circle)
			)
			(primitives
				(gr_poly
					(pts
						(arc
							(start -0.1778 -0.2794)
							(mid -0.249642 -0.249642)
							(end -0.2794 -0.1778)
						)
						(arc
							(start -0.2794 0.1778)
							(mid -0.249642 0.249642)
							(end -0.1778 0.2794)
						)
						(arc
							(start 0.1778 0.2794)
							(mid 0.249642 0.249642)
							(end 0.2794 0.1778)
						)
						(arc
							(start 0.2794 -0.1778)
							(mid 0.249642 -0.249642)
							(end 0.1778 -0.2794)
						)
					)
					(width 0)
					(fill yes)
				)
			)
		)
	)
	(footprint ""
		(layer "F.Cu")
		(at 70.204584 -301.29988 90)
		(property "Reference" "R565"
			(at 0 0 90)
			(layer "F.SilkS")
			(hide yes)
			(effects
				(font
					(size 1.27 1.27)
				)
			)
		)
		(property "Value" "4K7R2J-2-GP"
			(at 0.064008 -3.993896 90)
			(unlocked yes)
			(layer "F.Fab")
			(hide yes)
			(effects
				(font
					(size 1.016 1.016)
					(thickness 0.1524)
				)
			)
		)
		(property "Device Type" "R402H16"
			(at 0.064008 -5.517896 90)
			(unlocked yes)
			(layer "F.Fab")
			(hide yes)
			(effects
				(font
					(size 1.016 1.016)
					(thickness 0.1524)
				)
			)
		)
		(duplicate_pad_numbers_are_jumpers no)
		(fp_line
			(start 0.508 -0.9398)
			(end -0.508 -0.9398)
			(stroke
				(width 0.1524)
				(type default)
			)
			(layer "F.SilkS")
		)
		(fp_line
			(start -0.508 -0.9398)
			(end -0.508 0.9398)
			(stroke
				(width 0.1524)
				(type default)
			)
			(layer "F.SilkS")
		)
		(fp_rect
			(start -0.508 0.9398)
			(end 0.508 -0.9398)
			(stroke
				(width 0)
				(type default)
			)
			(fill no)
			(layer "F.CrtYd")
		)
		(fp_rect
			(start -0.508 0.9398)
			(end 0.508 -0.9398)
			(stroke
				(width 0)
				(type default)
			)
			(fill no)
			(layer "F.Fab")
		)
		(pad "1" smd custom
			(at 0 -0.4445 90)
			(size 0.1397 0.1397)
			(layers "F.Cu" "F.Mask" "F.Paste")
			(net "DRIVE_B_26_FLT_LED")
			(options
				(clearance outline)
				(anchor circle)
			)
			(primitives
				(gr_poly
					(pts
						(arc
							(start -0.1778 -0.2794)
							(mid -0.249642 -0.249642)
							(end -0.2794 -0.1778)
						)
						(arc
							(start -0.2794 0.1778)
							(mid -0.249642 0.249642)
							(end -0.1778 0.2794)
						)
						(arc
							(start 0.1778 0.2794)
							(mid 0.249642 0.249642)
							(end 0.2794 0.1778)
						)
						(arc
							(start 0.2794 -0.1778)
							(mid 0.249642 -0.249642)
							(end 0.1778 -0.2794)
						)
					)
					(width 0)
					(fill yes)
				)
			)
		)
		(pad "2" smd custom
			(at 0 0.4445 90)
			(size 0.1397 0.1397)
			(layers "F.Cu" "F.Mask" "F.Paste")
			(net "GND")
			(options
				(clearance outline)
				(anchor circle)
			)
			(primitives
				(gr_poly
					(pts
						(arc
							(start -0.1778 -0.2794)
							(mid -0.249642 -0.249642)
							(end -0.2794 -0.1778)
						)
						(arc
							(start -0.2794 0.1778)
							(mid -0.249642 0.249642)
							(end -0.1778 0.2794)
						)
						(arc
							(start 0.1778 0.2794)
							(mid 0.249642 0.249642)
							(end 0.2794 0.1778)
						)
						(arc
							(start 0.2794 -0.1778)
							(mid 0.249642 -0.249642)
							(end 0.1778 -0.2794)
						)
					)
					(width 0)
					(fill yes)
				)
			)
		)
	)
	(footprint ""
		(layer "F.Cu")
		(at 24.240998 -74.462894 180)
		(property "Reference" "C359"
			(at 0 0 180)
			(layer "F.SilkS")
			(hide yes)
			(effects
				(font
					(size 1.27 1.27)
				)
			)
		)
		(property "Value" "SC1U25V3KX-GP"
			(at 0 -2.8194 180)
			(unlocked yes)
			(layer "F.Fab")
			(hide yes)
			(effects
				(font
					(size 1.016 1.016)
					(thickness 0.1524)
				)
			)
		)
		(property "Device Type" "C603H36"
			(at 0 -4.3434 180)
			(unlocked yes)
			(layer "F.Fab")
			(hide yes)
			(effects
				(font
					(size 1.016 1.016)
					(thickness 0.1524)
				)
			)
		)
		(duplicate_pad_numbers_are_jumpers no)
		(fp_line
			(start 0.508 0)
			(end -0.508 0)
			(stroke
				(width 0.2032)
				(type default)
			)
			(layer "F.SilkS")
		)
		(fp_rect
			(start -0.5842 1.3335)
			(end 0.5842 -1.3335)
			(stroke
				(width 0)
				(type default)
			)
			(fill no)
			(layer "F.CrtYd")
		)
		(fp_rect
			(start -0.5842 1.3335)
			(end 0.5842 -1.3335)
			(stroke
				(width 0)
				(type default)
			)
			(fill no)
			(layer "F.Fab")
		)
		(pad "1" smd custom
			(at 0 -0.762 180)
			(size 0.2159 0.2159)
			(layers "F.Cu" "F.Mask" "F.Paste")
			(net "P12V_HDD24")
			(options
				(clearance outline)
				(anchor circle)
			)
			(primitives
				(gr_poly
					(pts
						(arc
							(start -0.3302 -0.4318)
							(mid -0.402042 -0.402042)
							(end -0.4318 -0.3302)
						)
						(arc
							(start -0.4318 0.3302)
							(mid -0.402042 0.402042)
							(end -0.3302 0.4318)
						)
						(arc
							(start 0.3302 0.4318)
							(mid 0.402042 0.402042)
							(end 0.4318 0.3302)
						)
						(arc
							(start 0.4318 -0.3302)
							(mid 0.402042 -0.402042)
							(end 0.3302 -0.4318)
						)
					)
					(width 0)
					(fill yes)
				)
			)
		)
		(pad "2" smd custom
			(at 0 0.762 180)
			(size 0.2159 0.2159)
			(layers "F.Cu" "F.Mask" "F.Paste")
			(net "GND")
			(options
				(clearance outline)
				(anchor circle)
			)
			(primitives
				(gr_poly
					(pts
						(arc
							(start -0.3302 -0.4318)
							(mid -0.402042 -0.402042)
							(end -0.4318 -0.3302)
						)
						(arc
							(start -0.4318 0.3302)
							(mid -0.402042 0.402042)
							(end -0.3302 0.4318)
						)
						(arc
							(start 0.3302 0.4318)
							(mid 0.402042 0.402042)
							(end 0.4318 0.3302)
						)
						(arc
							(start 0.4318 -0.3302)
							(mid 0.402042 -0.402042)
							(end 0.3302 -0.4318)
						)
					)
					(width 0)
					(fill yes)
				)
			)
		)
	)
	(footprint ""
		(layer "F.Cu")
		(at 14.715998 -64.683894 -90)
		(property "Reference" "C356"
			(at 0 0 270)
			(layer "F.SilkS")
			(hide yes)
			(effects
				(font
					(size 1.27 1.27)
				)
			)
		)
		(property "Value" "SC4D7U25V5KX-1-GP"
			(at -0.0762 -6.1214 270)
			(unlocked yes)
			(layer "F.Fab")
			(hide yes)
			(effects
				(font
					(size 1.016 1.016)
					(thickness 0.1524)
				)
			)
		)
		(property "Device Type" "C805H58"
			(at -0.0762 -8.1534 270)
			(unlocked yes)
			(layer "F.Fab")
			(hide yes)
			(effects
				(font
					(size 1.016 1.016)
					(thickness 0.1524)
				)
			)
		)
		(duplicate_pad_numbers_are_jumpers no)
		(fp_line
			(start 0.635 0)
			(end -0.635 0)
			(stroke
				(width 0.508)
				(type default)
			)
			(layer "F.SilkS")
		)
		(fp_rect
			(start -0.9652 1.778)
			(end 0.9652 -1.778)
			(stroke
				(width 0)
				(type default)
			)
			(fill no)
			(layer "F.CrtYd")
		)
		(fp_poly
			(pts
				(xy -0.9652 -1.778) (xy 0.9652 -1.778) (xy 0.9652 1.778) (xy -0.9652 1.778)
			)
			(stroke
				(width 0)
				(type default)
			)
			(fill no)
			(layer "F.Fab")
		)
		(pad "1" smd rect
			(at 0 -0.9652 270)
			(size 1.397 1.143)
			(layers "F.Cu" "F.Mask" "F.Paste")
			(net "P12V_HDD24")
		)
		(pad "2" smd rect
			(at 0 0.9652 270)
			(size 1.397 1.143)
			(layers "F.Cu" "F.Mask" "F.Paste")
			(net "GND")
		)
	)
	(footprint ""
		(layer "F.Cu")
		(at 433.359052 -57.851294 90)
		(property "Reference" "C478"
			(at 0 0 90)
			(layer "F.SilkS")
			(hide yes)
			(effects
				(font
					(size 1.27 1.27)
				)
			)
		)
		(property "Value" "SCD033U25V2KX-GP"
			(at 1.1811 -2.7051 90)
			(unlocked yes)
			(layer "F.Fab")
			(hide yes)
			(effects
				(font
					(size 1.016 1.016)
					(thickness 0.1524)
				)
			)
		)
		(property "Device Type" "C402H22"
			(at 1.1811 -4.2291 90)
			(unlocked yes)
			(layer "F.Fab")
			(hide yes)
			(effects
				(font
					(size 1.016 1.016)
					(thickness 0.1524)
				)
			)
		)
		(duplicate_pad_numbers_are_jumpers no)
		(fp_rect
			(start -0.4318 0.9525)
			(end 0.4318 -0.9525)
			(stroke
				(width 0)
				(type default)
			)
			(fill no)
			(layer "F.CrtYd")
		)
		(fp_rect
			(start -0.4318 0.9525)
			(end 0.4318 -0.9525)
			(stroke
				(width 0)
				(type default)
			)
			(fill no)
			(layer "F.Fab")
		)
		(pad "1" smd custom
			(at 0 -0.4445 90)
			(size 0.1524 0.1524)
			(layers "F.Cu" "F.Mask" "F.Paste")
			(net "P12V_A")
			(options
				(clearance outline)
				(anchor circle)
			)
			(primitives
				(gr_poly
					(pts
						(arc
							(start 0.3048 -0.2032)
							(mid 0.275042 -0.275042)
							(end 0.2032 -0.3048)
						)
						(arc
							(start -0.2032 -0.3048)
							(mid -0.275042 -0.275042)
							(end -0.3048 -0.2032)
						)
						(arc
							(start -0.3048 0.2032)
							(mid -0.275042 0.275042)
							(end -0.2032 0.3048)
						)
						(arc
							(start 0.2032 0.3048)
							(mid 0.275042 0.275042)
							(end 0.3048 0.2032)
						)
					)
					(width 0)
					(fill yes)
				)
			)
		)
		(pad "2" smd custom
			(at 0 0.4445 90)
			(size 0.1524 0.1524)
			(layers "F.Cu" "F.Mask" "F.Paste")
			(net "SW_HDD_N33")
			(options
				(clearance outline)
				(anchor circle)
			)
			(primitives
				(gr_poly
					(pts
						(arc
							(start 0.3048 -0.2032)
							(mid 0.275042 -0.275042)
							(end 0.2032 -0.3048)
						)
						(arc
							(start -0.2032 -0.3048)
							(mid -0.275042 -0.275042)
							(end -0.3048 -0.2032)
						)
						(arc
							(start -0.3048 0.2032)
							(mid -0.275042 0.275042)
							(end -0.2032 0.3048)
						)
						(arc
							(start 0.2032 0.3048)
							(mid 0.275042 0.275042)
							(end 0.3048 0.2032)
						)
					)
					(width 0)
					(fill yes)
				)
			)
		)
	)
	(footprint ""
		(layer "F.Cu")
		(at 345.410028 -127.254)
		(property "Reference" "R319"
			(at 0 0 0)
			(layer "F.SilkS")
			(hide yes)
			(effects
				(font
					(size 1.27 1.27)
				)
			)
		)
		(property "Value" "130R3F-GP"
			(at -0.0254 -2.5146 0)
			(unlocked yes)
			(layer "F.Fab")
			(hide yes)
			(effects
				(font
					(size 1.016 1.016)
					(thickness 0.1524)
				)
			)
		)
		(property "Device Type" "R603H22"
			(at -0.0254 -4.0386 0)
			(unlocked yes)
			(layer "F.Fab")
			(hide yes)
			(effects
				(font
					(size 1.016 1.016)
					(thickness 0.1524)
				)
			)
		)
		(duplicate_pad_numbers_are_jumpers no)
		(fp_line
			(start -0.4826 0)
			(end -0.2032 0)
			(stroke
				(width 0.2032)
				(type default)
			)
			(layer "F.SilkS")
		)
		(fp_line
			(start 0.2032 0)
			(end 0.4826 0)
			(stroke
				(width 0.2032)
				(type default)
			)
			(layer "F.SilkS")
		)
		(fp_rect
			(start -0.5842 1.3335)
			(end 0.5842 -1.3335)
			(stroke
				(width 0)
				(type default)
			)
			(fill no)
			(layer "F.CrtYd")
		)
		(fp_rect
			(start -0.5842 1.3335)
			(end 0.5842 -1.3335)
			(stroke
				(width 0)
				(type default)
			)
			(fill no)
			(layer "F.Fab")
		)
		(pad "1" smd custom
			(at 0 -0.762)
			(size 0.2159 0.2159)
			(layers "F.Cu" "F.Mask" "F.Paste")
			(net "P5V_A_3")
			(options
				(clearance outline)
				(anchor circle)
			)
			(primitives
				(gr_poly
					(pts
						(arc
							(start -0.3302 -0.4318)
							(mid -0.402042 -0.402042)
							(end -0.4318 -0.3302)
						)
						(arc
							(start -0.4318 0.3302)
							(mid -0.402042 0.402042)
							(end -0.3302 0.4318)
						)
						(arc
							(start 0.3302 0.4318)
							(mid 0.402042 0.402042)
							(end 0.4318 0.3302)
						)
						(arc
							(start 0.4318 -0.3302)
							(mid 0.402042 -0.402042)
							(end 0.3302 -0.4318)
						)
					)
					(width 0)
					(fill yes)
				)
			)
		)
		(pad "2" smd custom
			(at 0 0.762)
			(size 0.2159 0.2159)
			(layers "F.Cu" "F.Mask" "F.Paste")
			(net "FLT_HDD19")
			(options
				(clearance outline)
				(anchor circle)
			)
			(primitives
				(gr_poly
					(pts
						(arc
							(start -0.3302 -0.4318)
							(mid -0.402042 -0.402042)
							(end -0.4318 -0.3302)
						)
						(arc
							(start -0.4318 0.3302)
							(mid -0.402042 0.402042)
							(end -0.3302 0.4318)
						)
						(arc
							(start 0.3302 0.4318)
							(mid 0.402042 0.402042)
							(end 0.4318 0.3302)
						)
						(arc
							(start 0.4318 -0.3302)
							(mid 0.402042 -0.402042)
							(end 0.3302 -0.4318)
						)
					)
					(width 0)
					(fill yes)
				)
			)
		)
	)
	(footprint ""
		(layer "F.Cu")
		(at 369.624102 -49.443894 90)
		(property "Reference" "R859"
			(at 0 0 90)
			(layer "F.SilkS")
			(hide yes)
			(effects
				(font
					(size 1.27 1.27)
				)
			)
		)
		(property "Value" "200KR2F-L-GP"
			(at 0.064008 -3.993896 90)
			(unlocked yes)
			(layer "F.Fab")
			(hide yes)
			(effects
				(font
					(size 1.016 1.016)
					(thickness 0.1524)
				)
			)
		)
		(property "Device Type" "R402H16"
			(at 0.064008 -5.517896 90)
			(unlocked yes)
			(layer "F.Fab")
			(hide yes)
			(effects
				(font
					(size 1.016 1.016)
					(thickness 0.1524)
				)
			)
		)
		(duplicate_pad_numbers_are_jumpers no)
		(fp_line
			(start 0.508 -0.9398)
			(end -0.508 -0.9398)
			(stroke
				(width 0.1524)
				(type default)
			)
			(layer "F.SilkS")
		)
		(fp_line
			(start -0.508 -0.9398)
			(end -0.508 0.9398)
			(stroke
				(width 0.1524)
				(type default)
			)
			(layer "F.SilkS")
		)
		(fp_rect
			(start -0.508 0.9398)
			(end 0.508 -0.9398)
			(stroke
				(width 0)
				(type default)
			)
			(fill no)
			(layer "F.CrtYd")
		)
		(fp_rect
			(start -0.508 0.9398)
			(end 0.508 -0.9398)
			(stroke
				(width 0)
				(type default)
			)
			(fill no)
			(layer "F.Fab")
		)
		(pad "1" smd custom
			(at 0 -0.4445 90)
			(size 0.1397 0.1397)
			(layers "F.Cu" "F.Mask" "F.Paste")
			(net "SW_HDD_R31")
			(options
				(clearance outline)
				(anchor circle)
			)
			(primitives
				(gr_poly
					(pts
						(arc
							(start -0.1778 -0.2794)
							(mid -0.249642 -0.249642)
							(end -0.2794 -0.1778)
						)
						(arc
							(start -0.2794 0.1778)
							(mid -0.249642 0.249642)
							(end -0.1778 0.2794)
						)
						(arc
							(start 0.1778 0.2794)
							(mid 0.249642 0.249642)
							(end 0.2794 0.1778)
						)
						(arc
							(start 0.2794 -0.1778)
							(mid 0.249642 -0.249642)
							(end 0.1778 -0.2794)
						)
					)
					(width 0)
					(fill yes)
				)
			)
		)
		(pad "2" smd custom
			(at 0 0.4445 90)
			(size 0.1397 0.1397)
			(layers "F.Cu" "F.Mask" "F.Paste")
			(net "SW_HDD_N31")
			(options
				(clearance outline)
				(anchor circle)
			)
			(primitives
				(gr_poly
					(pts
						(arc
							(start -0.1778 -0.2794)
							(mid -0.249642 -0.249642)
							(end -0.2794 -0.1778)
						)
						(arc
							(start -0.2794 0.1778)
							(mid -0.249642 0.249642)
							(end -0.1778 0.2794)
						)
						(arc
							(start 0.1778 0.2794)
							(mid 0.249642 0.249642)
							(end 0.2794 0.1778)
						)
						(arc
							(start 0.2794 -0.1778)
							(mid 0.249642 -0.249642)
							(end 0.1778 -0.2794)
						)
					)
					(width 0)
					(fill yes)
				)
			)
		)
	)
	(footprint ""
		(layer "F.Cu")
		(at 14.792198 -275.608542 90)
		(property "Reference" "R972"
			(at 0 0 90)
			(layer "F.SilkS")
			(hide yes)
			(effects
				(font
					(size 1.27 1.27)
				)
			)
		)
		(property "Value" "4K7R2J-2-GP"
			(at 0.064008 -3.993896 90)
			(unlocked yes)
			(layer "F.Fab")
			(hide yes)
			(effects
				(font
					(size 1.016 1.016)
					(thickness 0.1524)
				)
			)
		)
		(property "Device Type" "R402H16"
			(at 0.064008 -5.517896 90)
			(unlocked yes)
			(layer "F.Fab")
			(hide yes)
			(effects
				(font
					(size 1.016 1.016)
					(thickness 0.1524)
				)
			)
		)
		(duplicate_pad_numbers_are_jumpers no)
		(fp_line
			(start 0.508 -0.9398)
			(end -0.508 -0.9398)
			(stroke
				(width 0.1524)
				(type default)
			)
			(layer "F.SilkS")
		)
		(fp_line
			(start -0.508 -0.9398)
			(end -0.508 0.9398)
			(stroke
				(width 0.1524)
				(type default)
			)
			(layer "F.SilkS")
		)
		(fp_rect
			(start -0.508 0.9398)
			(end 0.508 -0.9398)
			(stroke
				(width 0)
				(type default)
			)
			(fill no)
			(layer "F.CrtYd")
		)
		(fp_rect
			(start -0.508 0.9398)
			(end 0.508 -0.9398)
			(stroke
				(width 0)
				(type default)
			)
			(fill no)
			(layer "F.Fab")
		)
		(pad "1" smd custom
			(at 0 -0.4445 90)
			(size 0.1397 0.1397)
			(layers "F.Cu" "F.Mask" "F.Paste")
			(net "P12V_A")
			(options
				(clearance outline)
				(anchor circle)
			)
			(primitives
				(gr_poly
					(pts
						(arc
							(start -0.1778 -0.2794)
							(mid -0.249642 -0.249642)
							(end -0.2794 -0.1778)
						)
						(arc
							(start -0.2794 0.1778)
							(mid -0.249642 0.249642)
							(end -0.1778 0.2794)
						)
						(arc
							(start 0.1778 0.2794)
							(mid 0.249642 0.249642)
							(end 0.2794 0.1778)
						)
						(arc
							(start 0.2794 -0.1778)
							(mid 0.249642 -0.249642)
							(end 0.1778 -0.2794)
						)
					)
					(width 0)
					(fill yes)
				)
			)
		)
		(pad "2" smd custom
			(at 0 0.4445 90)
			(size 0.1397 0.1397)
			(layers "F.Cu" "F.Mask" "F.Paste")
			(net "SW_HDD_R0")
			(options
				(clearance outline)
				(anchor circle)
			)
			(primitives
				(gr_poly
					(pts
						(arc
							(start -0.1778 -0.2794)
							(mid -0.249642 -0.249642)
							(end -0.2794 -0.1778)
						)
						(arc
							(start -0.2794 0.1778)
							(mid -0.249642 0.249642)
							(end -0.1778 0.2794)
						)
						(arc
							(start 0.1778 0.2794)
							(mid 0.249642 0.249642)
							(end 0.2794 0.1778)
						)
						(arc
							(start 0.2794 -0.1778)
							(mid 0.249642 -0.249642)
							(end 0.1778 -0.2794)
						)
					)
					(width 0)
					(fill yes)
				)
			)
		)
	)
)
